# T6G (Grand Teton) — schematic netlist excerpt (pin names and nets, part order shuffled) for the footprints in the layout excerpt that follows; sources: Cadence DE-HDL packaged netlist, KiCad conversion of 04192023_DAF0TMB3IC0_F0TG_MB_C_brd_V02_OCP.brd

PJ1  CONN3_210HP1030BR1  CONN3_210-HP1-030BR1 IO  pkg HEADER1X3XG  page 193
  \1\  = GND
  \2\  = SMB_SCM_2_R3_SDA
  \3\  = SMB_SCM_2_R3_SCL

R582  Q_RES  4.7K 5% EMPTY  pkg 0402LF  page 28 : A = GND ; B = RST_CPU0_RSMRST_N
C6596  Q_CAP_DIFFBUS  DIFF BUS_0.22UF 6.3V 20% X6S  pkg C0201  page 297 : \1\ = P5E_CPU0_P2_TX_BUF_C_DN<15> ; \2\ = P5E_CPU0_P2_TX_BUF_DN<15>

(kicad_pcb
	(version 20260206)
	(generator "pcbnew")
	(generator_version "10.0")
	(general
		(thickness 1.6)
		(legacy_teardrops no)
	)
	(paper "A4")
	(title_block
		(title "04192023_DAF0TMB3IC0_F0TG_MB_C_brd_V02_OCP.brd")
		(comment 1 "Grand Teton / footprints 3337-3339 of 8354")
	)
	(layers
		(0 "F.Cu" signal "TOP")
		(4 "In1.Cu" signal "GND")
		(6 "In2.Cu" signal "IN1")
		(8 "In3.Cu" signal "GND1")
		(10 "In4.Cu" signal "IN2")
		(12 "In5.Cu" signal "GND2")
		(14 "In6.Cu" signal "IN3")
		(16 "In7.Cu" signal "GND3")
		(18 "In8.Cu" signal "VCC")
		(20 "In9.Cu" signal "VCC1")
		(22 "In10.Cu" signal "GND4")
		(24 "In11.Cu" signal "IN4")
		(26 "In12.Cu" signal "GND5")
		(28 "In13.Cu" signal "IN5")
		(30 "In14.Cu" signal "GND6")
		(32 "In15.Cu" signal "IN6")
		(34 "In16.Cu" signal "GND7")
		(2 "B.Cu" signal "BOTTOM")
		(9 "F.Adhes" user "F.Adhesive")
		(11 "B.Adhes" user "B.Adhesive")
		(13 "F.Paste" user "Package Geometry/Pastemask Top")
		(15 "B.Paste" user "Package Geometry/Pastemask Bottom")
		(5 "F.SilkS" user "Ref Des/Silkscreen Top")
		(7 "B.SilkS" user "Ref Des/Silkscreen Bottom")
		(1 "F.Mask" user "Board Geometry/Soldermask Top")
		(3 "B.Mask" user "Board Geometry/Soldermask Bottom")
		(17 "Dwgs.User" user "User.Drawings")
		(19 "Cmts.User" user "User.Comments")
		(21 "Eco1.User" user "User.Eco1")
		(23 "Eco2.User" user "User.Eco2")
		(25 "Edge.Cuts" user "Board Geometry/Outline")
		(27 "Margin" user)
		(31 "F.CrtYd" user "Package Geometry/Place Bound Top")
		(29 "B.CrtYd" user "Package Geometry/Place Bound Bottom")
		(35 "F.Fab" user "Ref Des/Assembly Top")
		(33 "B.Fab" user "Ref Des/Assembly Bottom")
	)
	(footprint ""
		(layer "F.Cu")
		(at 416.817302 -416.899344 -90)
		(property "Reference" "C6596"
			(at 0 0 270)
			(layer "F.SilkS")
			(hide yes)
			(effects
				(font
					(size 1.27 1.27)
				)
			)
		)
		(property "Value" ""
			(at 0 0 270)
			(layer "F.Fab")
			(effects
				(font
					(size 1.27 1.27)
				)
			)
		)
		(duplicate_pad_numbers_are_jumpers no)
		(fp_line
			(start -0.299974 0.150114)
			(end -0.299974 -0.150114)
			(stroke
				(width 0.1)
				(type default)
			)
			(layer "F.Fab")
		)
		(fp_line
			(start 0.299974 0.150114)
			(end -0.299974 0.150114)
			(stroke
				(width 0.1)
				(type default)
			)
			(layer "F.Fab")
		)
		(fp_line
			(start -0.299974 -0.150114)
			(end 0.299974 -0.150114)
			(stroke
				(width 0.1)
				(type default)
			)
			(layer "F.Fab")
		)
		(fp_line
			(start 0.299974 -0.150114)
			(end 0.299974 0.150114)
			(stroke
				(width 0.1)
				(type default)
			)
			(layer "F.Fab")
		)
		(pad "1" smd rect
			(at -0.2667 0 270)
			(size 0.3048 0.381)
			(layers "F.Cu" "F.Mask" "F.Paste")
			(net "P5E_CPU0_P2_TX_BUF_C_DN<15>")
		)
		(pad "2" smd rect
			(at 0.2667 0 270)
			(size 0.3048 0.381)
			(layers "F.Cu" "F.Mask" "F.Paste")
			(net "P5E_CPU0_P2_TX_BUF_DN<15>")
		)
	)
	(footprint ""
		(layer "F.Cu")
		(at 393.795758 -147.663662 -90)
		(property "Reference" "PJ1"
			(at 2.030476 0.681228 0)
			(unlocked yes)
			(layer "F.SilkS")
			(effects
				(font
					(size 0.7874 0.5842)
					(thickness 0.1524)
				)
				(justify left)
			)
		)
		(property "Value" ""
			(at 0 0 270)
			(layer "F.Fab")
			(effects
				(font
					(size 1.27 1.27)
				)
			)
		)
		(duplicate_pad_numbers_are_jumpers no)
		(fp_line
			(start -1.249934 6.400038)
			(end -1.249934 -1.320038)
			(stroke
				(width 0.1524)
				(type default)
			)
			(layer "F.SilkS")
		)
		(fp_line
			(start 1.249934 6.400038)
			(end -1.249934 6.400038)
			(stroke
				(width 0.1524)
				(type default)
			)
			(layer "F.SilkS")
		)
		(fp_line
			(start -1.249934 -1.320038)
			(end 1.249934 -1.320038)
			(stroke
				(width 0.1524)
				(type default)
			)
			(layer "F.SilkS")
		)
		(fp_line
			(start 1.249934 -1.320038)
			(end 1.249934 6.400038)
			(stroke
				(width 0.1524)
				(type default)
			)
			(layer "F.SilkS")
		)
		(fp_poly
			(pts
				(xy -2.5654 -0.556514) (xy -1.452372 0) (xy -2.5654 0.556514)
			)
			(stroke
				(width 0)
				(type default)
			)
			(fill yes)
			(layer "F.SilkS")
		)
		(fp_line
			(start -1.249934 6.400038)
			(end -1.249934 -1.320038)
			(stroke
				(width 0.1)
				(type default)
			)
			(layer "F.Fab")
		)
		(fp_line
			(start 1.249934 6.400038)
			(end -1.249934 6.400038)
			(stroke
				(width 0.1)
				(type default)
			)
			(layer "F.Fab")
		)
		(fp_line
			(start -1.249934 -1.320038)
			(end 1.249934 -1.320038)
			(stroke
				(width 0.1)
				(type default)
			)
			(layer "F.Fab")
		)
		(fp_line
			(start 1.249934 -1.320038)
			(end 1.249934 6.400038)
			(stroke
				(width 0.1)
				(type default)
			)
			(layer "F.Fab")
		)
		(fp_poly
			(pts
				(xy -2.5654 -0.556514) (xy -1.452372 0) (xy -2.5654 0.556514)
			)
			(stroke
				(width 0)
				(type default)
			)
			(fill yes)
			(layer "F.Fab")
		)
		(fp_text user "3"
			(at -2.003806 5.113528 0)
			(unlocked yes)
			(layer "F.SilkS")
			(effects
				(font
					(size 0.7874 0.5842)
					(thickness 0.1524)
				)
			)
		)
		(fp_text user "3"
			(at -1.1557 5.18287 270)
			(unlocked yes)
			(layer "B.SilkS")
			(effects
				(font
					(size 0.7874 0.5842)
					(thickness 0.1524)
				)
				(justify mirror)
			)
		)
		(fp_text user "1"
			(at -1.143 0.02667 270)
			(unlocked yes)
			(layer "B.SilkS")
			(effects
				(font
					(size 0.7874 0.5842)
					(thickness 0.1524)
				)
				(justify mirror)
			)
		)
		(fp_text user "3"
			(at -1.1557 5.18287 270)
			(unlocked yes)
			(layer "B.Fab")
			(effects
				(font
					(size 0.7874 0.5842)
					(thickness 0.1524)
				)
				(justify mirror)
			)
		)
		(fp_text user "1"
			(at -1.143 0.02667 270)
			(unlocked yes)
			(layer "B.Fab")
			(effects
				(font
					(size 0.7874 0.5842)
					(thickness 0.1524)
				)
				(justify mirror)
			)
		)
		(fp_text user "3"
			(at -1.778 5.13207 270)
			(unlocked yes)
			(layer "F.Fab")
			(effects
				(font
					(size 0.7874 0.5842)
					(thickness 0.1524)
				)
			)
		)
		(pad "1" thru_hole rect
			(at 0 0 270)
			(size 1.5494 1.5494)
			(drill 1.0414)
			(layers "*.Cu" "*.Mask")
			(remove_unused_layers no)
			(net "GND")
			(clearance 0)
			(padstack
				(mode front_inner_back)
				(layer "Inner"
					(shape circle)
					(size 1.5494 1.5494)
					(clearance 0)
				)
				(layer "B.Cu"
					(shape rect)
					(size 1.5494 1.5494)
					(clearance 0)
				)
			)
		)
		(pad "2" thru_hole circle
			(at 0 2.54 270)
			(size 1.5494 1.5494)
			(drill 1.0414)
			(layers "*.Cu" "*.Mask")
			(remove_unused_layers no)
			(net "SMB_SCM_2_R3_SDA")
			(clearance 0)
		)
		(pad "3" thru_hole circle
			(at 0 5.08 270)
			(size 1.5494 1.5494)
			(drill 1.0414)
			(layers "*.Cu" "*.Mask")
			(remove_unused_layers no)
			(net "SMB_SCM_2_R3_SCL")
			(clearance 0)
		)
	)
	(footprint ""
		(layer "F.Cu")
		(at 393.363196 -321.632834)
		(property "Reference" "R582"
			(at 0 0 0)
			(layer "F.SilkS")
			(hide yes)
			(effects
				(font
					(size 1.27 1.27)
				)
			)
		)
		(property "Value" ""
			(at 0 0 0)
			(layer "F.Fab")
			(effects
				(font
					(size 1.27 1.27)
				)
			)
		)
		(duplicate_pad_numbers_are_jumpers no)
		(fp_line
			(start -0.7874 -0.4064)
			(end 0.7874 -0.4064)
			(stroke
				(width 0.1524)
				(type default)
			)
			(layer "F.SilkS")
		)
		(fp_line
			(start -0.7874 0.4064)
			(end -0.7874 -0.4064)
			(stroke
				(width 0.1524)
				(type default)
			)
			(layer "F.SilkS")
		)
		(fp_line
			(start 0.7874 -0.4064)
			(end 0.7874 0.4064)
			(stroke
				(width 0.1524)
				(type default)
			)
			(layer "F.SilkS")
		)
		(fp_line
			(start 0.7874 0.4064)
			(end -0.7874 0.4064)
			(stroke
				(width 0.1524)
				(type default)
			)
			(layer "F.SilkS")
		)
		(fp_line
			(start -0.67945 -0.305054)
			(end -0.12065 -0.305054)
			(stroke
				(width 0.1)
				(type default)
			)
			(layer "F.Fab")
		)
		(fp_line
			(start -0.67945 0.3048)
			(end -0.67945 -0.305054)
			(stroke
				(width 0.1)
				(type default)
			)
			(layer "F.Fab")
		)
		(fp_line
			(start -0.12065 -0.305054)
			(end -0.12065 -0.2794)
			(stroke
				(width 0.1)
				(type default)
			)
			(layer "F.Fab")
		)
		(fp_line
			(start -0.12065 -0.2794)
			(end 0.12065 -0.2794)
			(stroke
				(width 0.1)
				(type default)
			)
			(layer "F.Fab")
		)
		(fp_line
			(start -0.12065 0.2794)
			(end -0.12065 0.3048)
			(stroke
				(width 0.1)
				(type default)
			)
			(layer "F.Fab")
		)
		(fp_line
			(start -0.12065 0.3048)
			(end -0.67945 0.3048)
			(stroke
				(width 0.1)
				(type default)
			)
			(layer "F.Fab")
		)
		(fp_line
			(start 0.120396 0.2794)
			(end -0.12065 0.2794)
			(stroke
				(width 0.1)
				(type default)
			)
			(layer "F.Fab")
		)
		(fp_line
			(start 0.120396 0.3048)
			(end 0.120396 0.2794)
			(stroke
				(width 0.1)
				(type default)
			)
			(layer "F.Fab")
		)
		(fp_line
			(start 0.12065 -0.3048)
			(end 0.67945 -0.3048)
			(stroke
				(width 0.1)
				(type default)
			)
			(layer "F.Fab")
		)
		(fp_line
			(start 0.12065 -0.2794)
			(end 0.12065 -0.3048)
			(stroke
				(width 0.1)
				(type default)
			)
			(layer "F.Fab")
		)
		(fp_line
			(start 0.67945 -0.3048)
			(end 0.67945 0.3048)
			(stroke
				(width 0.1)
				(type default)
			)
			(layer "F.Fab")
		)
		(fp_line
			(start 0.67945 0.3048)
			(end 0.120396 0.3048)
			(stroke
				(width 0.1)
				(type default)
			)
			(layer "F.Fab")
		)
		(pad "1" smd circle
			(at -0.40005 0)
			(size 0 0)
			(layers "F.Cu" "F.Mask" "F.Paste")
			(net "GND")
		)
		(pad "2" smd circle
			(at 0.40005 0)
			(size 0 0)
			(layers "F.Cu" "F.Mask" "F.Paste")
			(net "RST_CPU0_RSMRST_N")
		)
	)
)
